# SCM (Grand Teton) — schematic netlist excerpt (pin names and nets, part order shuffled) for the footprints in the layout excerpt that follows; sources: Cadence DE-HDL packaged netlist, KiCad conversion of 12092022_DA0F0TMDCD0_F0T_Management_Board_D_brd_V3_OCP.brd

PC273  Q_CAP  3300PF 50V 10% X7R  pkg 0402  page 52 : A = P3V3_AUX_REF ; B = GND
C181  Q_CAP  0.1UF 25V 10% X7R  pkg 0402  page 50 : A = REAR_AC_PWR_BTN ; B = GND

(kicad_pcb
	(version 20260206)
	(generator "pcbnew")
	(generator_version "10.0")
	(general
		(thickness 1.6)
		(legacy_teardrops no)
	)
	(paper "A4")
	(title_block
		(title "12092022_DA0F0TMDCD0_F0T_Management_Board_D_brd_V3_OCP.brd")
		(comment 1 "Grand Teton / footprints 79-80 of 1440")
	)
	(layers
		(0 "F.Cu" signal "TOP")
		(4 "In1.Cu" signal "GND")
		(6 "In2.Cu" signal "IN1")
		(8 "In3.Cu" signal "GND1")
		(10 "In4.Cu" signal "IN2")
		(12 "In5.Cu" signal "VCC")
		(14 "In6.Cu" signal "VCC1")
		(16 "In7.Cu" signal "IN3")
		(18 "In8.Cu" signal "GND2")
		(20 "In9.Cu" signal "IN4")
		(22 "In10.Cu" signal "GND3")
		(2 "B.Cu" signal "BOTTOM")
		(9 "F.Adhes" user "F.Adhesive")
		(11 "B.Adhes" user "B.Adhesive")
		(13 "F.Paste" user "Package Geometry/Pastemask Top")
		(15 "B.Paste" user "Package Geometry/Pastemask Bottom")
		(5 "F.SilkS" user "Ref Des/Silkscreen Top")
		(7 "B.SilkS" user "Ref Des/Silkscreen Bottom")
		(1 "F.Mask" user "Board Geometry/Soldermask Top")
		(3 "B.Mask" user "Board Geometry/Soldermask Bottom")
		(17 "Dwgs.User" user "User.Drawings")
		(19 "Cmts.User" user "User.Comments")
		(21 "Eco1.User" user "User.Eco1")
		(23 "Eco2.User" user "User.Eco2")
		(25 "Edge.Cuts" user "Board Geometry/Outline")
		(27 "Margin" user)
		(31 "F.CrtYd" user "Package Geometry/Place Bound Top")
		(29 "B.CrtYd" user "Package Geometry/Place Bound Bottom")
		(35 "F.Fab" user "Ref Des/Assembly Top")
		(33 "B.Fab" user "Ref Des/Assembly Bottom")
	)
	(footprint ""
		(layer "F.Cu")
		(at 73.72223 -10.922762 90)
		(property "Reference" "C181"
			(at 0 0 90)
			(layer "F.SilkS")
			(hide yes)
			(effects
				(font
					(size 1.27 1.27)
				)
			)
		)
		(property "Value" ""
			(at 0 0 90)
			(layer "F.Fab")
			(effects
				(font
					(size 1.27 1.27)
				)
			)
		)
		(duplicate_pad_numbers_are_jumpers no)
		(fp_line
			(start 0.7874 -0.4064)
			(end 0.7874 0.4064)
			(stroke
				(width 0.1524)
				(type default)
			)
			(layer "F.SilkS")
		)
		(fp_line
			(start -0.7874 -0.4064)
			(end 0.7874 -0.4064)
			(stroke
				(width 0.1524)
				(type default)
			)
			(layer "F.SilkS")
		)
		(fp_line
			(start 0.7874 0.4064)
			(end -0.7874 0.4064)
			(stroke
				(width 0.1524)
				(type default)
			)
			(layer "F.SilkS")
		)
		(fp_line
			(start -0.7874 0.4064)
			(end -0.7874 -0.4064)
			(stroke
				(width 0.1524)
				(type default)
			)
			(layer "F.SilkS")
		)
		(fp_line
			(start -0.12065 -0.305054)
			(end -0.12065 -0.2794)
			(stroke
				(width 0.1)
				(type default)
			)
			(layer "F.Fab")
		)
		(fp_line
			(start -0.67945 -0.305054)
			(end -0.12065 -0.305054)
			(stroke
				(width 0.1)
				(type default)
			)
			(layer "F.Fab")
		)
		(fp_line
			(start 0.67945 -0.3048)
			(end 0.67945 0.3048)
			(stroke
				(width 0.1)
				(type default)
			)
			(layer "F.Fab")
		)
		(fp_line
			(start 0.12065 -0.3048)
			(end 0.67945 -0.3048)
			(stroke
				(width 0.1)
				(type default)
			)
			(layer "F.Fab")
		)
		(fp_line
			(start 0.12065 -0.2794)
			(end 0.12065 -0.3048)
			(stroke
				(width 0.1)
				(type default)
			)
			(layer "F.Fab")
		)
		(fp_line
			(start -0.12065 -0.2794)
			(end 0.12065 -0.2794)
			(stroke
				(width 0.1)
				(type default)
			)
			(layer "F.Fab")
		)
		(fp_line
			(start 0.120396 0.2794)
			(end -0.12065 0.2794)
			(stroke
				(width 0.1)
				(type default)
			)
			(layer "F.Fab")
		)
		(fp_line
			(start -0.12065 0.2794)
			(end -0.12065 0.3048)
			(stroke
				(width 0.1)
				(type default)
			)
			(layer "F.Fab")
		)
		(fp_line
			(start 0.67945 0.3048)
			(end 0.120396 0.3048)
			(stroke
				(width 0.1)
				(type default)
			)
			(layer "F.Fab")
		)
		(fp_line
			(start 0.120396 0.3048)
			(end 0.120396 0.2794)
			(stroke
				(width 0.1)
				(type default)
			)
			(layer "F.Fab")
		)
		(fp_line
			(start -0.12065 0.3048)
			(end -0.67945 0.3048)
			(stroke
				(width 0.1)
				(type default)
			)
			(layer "F.Fab")
		)
		(fp_line
			(start -0.67945 0.3048)
			(end -0.67945 -0.305054)
			(stroke
				(width 0.1)
				(type default)
			)
			(layer "F.Fab")
		)
		(pad "1" smd circle
			(at -0.40005 0 90)
			(size 0 0)
			(layers "F.Cu" "F.Mask" "F.Paste")
			(net "REAR_AC_PWR_BTN")
		)
		(pad "2" smd circle
			(at 0.40005 0 90)
			(size 0 0)
			(layers "F.Cu" "F.Mask" "F.Paste")
			(net "GND")
		)
	)
	(footprint ""
		(layer "F.Cu")
		(at 10.897616 -65.948052)
		(property "Reference" "PC273"
			(at 0 0 0)
			(layer "F.SilkS")
			(hide yes)
			(effects
				(font
					(size 1.27 1.27)
				)
			)
		)
		(property "Value" ""
			(at 0 0 0)
			(layer "F.Fab")
			(effects
				(font
					(size 1.27 1.27)
				)
			)
		)
		(duplicate_pad_numbers_are_jumpers no)
		(fp_line
			(start -0.7874 -0.4064)
			(end 0.7874 -0.4064)
			(stroke
				(width 0.1524)
				(type default)
			)
			(layer "F.SilkS")
		)
		(fp_line
			(start -0.7874 0.4064)
			(end -0.7874 -0.4064)
			(stroke
				(width 0.1524)
				(type default)
			)
			(layer "F.SilkS")
		)
		(fp_line
			(start 0.7874 -0.4064)
			(end 0.7874 0.4064)
			(stroke
				(width 0.1524)
				(type default)
			)
			(layer "F.SilkS")
		)
		(fp_line
			(start 0.7874 0.4064)
			(end -0.7874 0.4064)
			(stroke
				(width 0.1524)
				(type default)
			)
			(layer "F.SilkS")
		)
		(fp_line
			(start -0.67945 -0.305054)
			(end -0.12065 -0.305054)
			(stroke
				(width 0.1)
				(type default)
			)
			(layer "F.Fab")
		)
		(fp_line
			(start -0.67945 0.3048)
			(end -0.67945 -0.305054)
			(stroke
				(width 0.1)
				(type default)
			)
			(layer "F.Fab")
		)
		(fp_line
			(start -0.12065 -0.305054)
			(end -0.12065 -0.2794)
			(stroke
				(width 0.1)
				(type default)
			)
			(layer "F.Fab")
		)
		(fp_line
			(start -0.12065 -0.2794)
			(end 0.12065 -0.2794)
			(stroke
				(width 0.1)
				(type default)
			)
			(layer "F.Fab")
		)
		(fp_line
			(start -0.12065 0.2794)
			(end -0.12065 0.3048)
			(stroke
				(width 0.1)
				(type default)
			)
			(layer "F.Fab")
		)
		(fp_line
			(start -0.12065 0.3048)
			(end -0.67945 0.3048)
			(stroke
				(width 0.1)
				(type default)
			)
			(layer "F.Fab")
		)
		(fp_line
			(start 0.120396 0.2794)
			(end -0.12065 0.2794)
			(stroke
				(width 0.1)
				(type default)
			)
			(layer "F.Fab")
		)
		(fp_line
			(start 0.120396 0.3048)
			(end 0.120396 0.2794)
			(stroke
				(width 0.1)
				(type default)
			)
			(layer "F.Fab")
		)
		(fp_line
			(start 0.12065 -0.3048)
			(end 0.67945 -0.3048)
			(stroke
				(width 0.1)
				(type default)
			)
			(layer "F.Fab")
		)
		(fp_line
			(start 0.12065 -0.2794)
			(end 0.12065 -0.3048)
			(stroke
				(width 0.1)
				(type default)
			)
			(layer "F.Fab")
		)
		(fp_line
			(start 0.67945 -0.3048)
			(end 0.67945 0.3048)
			(stroke
				(width 0.1)
				(type default)
			)
			(layer "F.Fab")
		)
		(fp_line
			(start 0.67945 0.3048)
			(end 0.120396 0.3048)
			(stroke
				(width 0.1)
				(type default)
			)
			(layer "F.Fab")
		)
		(pad "1" smd circle
			(at -0.40005 0)
			(size 0 0)
			(layers "F.Cu" "F.Mask" "F.Paste")
			(net "P3V3_AUX_REF")
		)
		(pad "2" smd circle
			(at 0.40005 0)
			(size 0 0)
			(layers "F.Cu" "F.Mask" "F.Paste")
			(net "GND")
		)
	)
)
